(kicad_pcb
	(version 20260206)
	(generator "pcbnew")
	(generator_version "10.0")
	(general
		(thickness 1.6)
		(legacy_teardrops no)
	)
	(paper "A4")
	(title_block
		(title "pdpb — Lightning_PDPB_BRD.brd")
		(comment 1 "Lightning (Wiwynn / Facebook NVMe JBOF) / footprints 1117-1122 of 1140")
	)
	(layers
		(0 "F.Cu" signal "TOP")
		(4 "In1.Cu" signal "L2GND")
		(6 "In2.Cu" signal "L3")
		(8 "In3.Cu" signal "L4VCC")
		(10 "In4.Cu" signal "L5VCC")
		(12 "In5.Cu" signal "L6")
		(14 "In6.Cu" signal "L7GND")
		(2 "B.Cu" signal "BOTTOM")
		(9 "F.Adhes" user "F.Adhesive")
		(11 "B.Adhes" user "B.Adhesive")
		(13 "F.Paste" user "Package Geometry/Pastemask Top")
		(15 "B.Paste" user "Package Geometry/Pastemask Bottom")
		(5 "F.SilkS" user "Ref Des/Silkscreen Top")
		(7 "B.SilkS" user "Ref Des/Silkscreen Bottom")
		(1 "F.Mask" user "Board Geometry/Soldermask Top")
		(3 "B.Mask" user "Board Geometry/Soldermask Bottom")
		(17 "Dwgs.User" user "User.Drawings")
		(19 "Cmts.User" user "User.Comments")
		(21 "Eco1.User" user "User.Eco1")
		(23 "Eco2.User" user "User.Eco2")
		(25 "Edge.Cuts" user "Board Geometry/Outline")
		(27 "Margin" user)
		(31 "F.CrtYd" user "Package Geometry/Place Bound Top")
		(29 "B.CrtYd" user "Package Geometry/Place Bound Bottom")
		(35 "F.Fab" user "Ref Des/Assembly Top")
		(33 "B.Fab" user "Ref Des/Assembly Bottom")
	)
	(footprint ""
		(layer "F.Cu")
		(at 90.043 -89.535 90)
		(property "Reference" "C9339"
			(at 0 0 90)
			(layer "F.SilkS")
			(hide yes)
			(effects
				(font
					(size 1.27 1.27)
				)
			)
		)
		(property "Value" "SC1KP50V2KX-1GP"
			(at 1.1811 -2.7051 90)
			(unlocked yes)
			(layer "F.Fab")
			(hide yes)
			(effects
				(font
					(size 1.016 1.016)
					(thickness 0.1524)
				)
			)
		)
		(property "Device Type" "C402H22"
			(at 1.1811 -4.2291 90)
			(unlocked yes)
			(layer "F.Fab")
			(hide yes)
			(effects
				(font
					(size 1.016 1.016)
					(thickness 0.1524)
				)
			)
		)
		(duplicate_pad_numbers_are_jumpers no)
		(fp_rect
			(start -0.4318 0.9525)
			(end 0.4318 -0.9525)
			(stroke
				(width 0)
				(type default)
			)
			(fill no)
			(layer "F.CrtYd")
		)
		(fp_rect
			(start -0.4318 0.9525)
			(end 0.4318 -0.9525)
			(stroke
				(width 0)
				(type default)
			)
			(fill no)
			(layer "F.Fab")
		)
		(pad "1" smd custom
			(at 0 -0.4445 90)
			(size 0.1524 0.1524)
			(layers "F.Cu" "F.Mask" "F.Paste")
			(net "SSD9_CLK0_OE_R_N")
			(options
				(clearance outline)
				(anchor circle)
			)
			(primitives
				(gr_poly
					(pts
						(arc
							(start 0.3048 -0.2032)
							(mid 0.275042 -0.275042)
							(end 0.2032 -0.3048)
						)
						(arc
							(start -0.2032 -0.3048)
							(mid -0.275042 -0.275042)
							(end -0.3048 -0.2032)
						)
						(arc
							(start -0.3048 0.2032)
							(mid -0.275042 0.275042)
							(end -0.2032 0.3048)
						)
						(arc
							(start 0.2032 0.3048)
							(mid 0.275042 0.275042)
							(end 0.3048 0.2032)
						)
					)
					(width 0)
					(fill yes)
				)
			)
		)
		(pad "2" smd custom
			(at 0 0.4445 90)
			(size 0.1524 0.1524)
			(layers "F.Cu" "F.Mask" "F.Paste")
			(net "GND")
			(options
				(clearance outline)
				(anchor circle)
			)
			(primitives
				(gr_poly
					(pts
						(arc
							(start 0.3048 -0.2032)
							(mid 0.275042 -0.275042)
							(end 0.2032 -0.3048)
						)
						(arc
							(start -0.2032 -0.3048)
							(mid -0.275042 -0.275042)
							(end -0.3048 -0.2032)
						)
						(arc
							(start -0.3048 0.2032)
							(mid -0.275042 0.275042)
							(end -0.2032 0.3048)
						)
						(arc
							(start 0.2032 0.3048)
							(mid 0.275042 0.275042)
							(end 0.3048 0.2032)
						)
					)
					(width 0)
					(fill yes)
				)
			)
		)
	)
	(footprint ""
		(layer "F.Cu")
		(at 84.455 -95.758 90)
		(property "Reference" "PR9041"
			(at 0 0 90)
			(layer "F.SilkS")
			(hide yes)
			(effects
				(font
					(size 1.27 1.27)
				)
			)
		)
		(property "Value" "4K7R2F-GP"
			(at 0.064008 -3.993896 90)
			(unlocked yes)
			(layer "F.Fab")
			(hide yes)
			(effects
				(font
					(size 1.016 1.016)
					(thickness 0.1524)
				)
			)
		)
		(property "Device Type" "R402H16"
			(at 0.064008 -5.517896 90)
			(unlocked yes)
			(layer "F.Fab")
			(hide yes)
			(effects
				(font
					(size 1.016 1.016)
					(thickness 0.1524)
				)
			)
		)
		(duplicate_pad_numbers_are_jumpers no)
		(fp_line
			(start 0.508 -0.9398)
			(end -0.508 -0.9398)
			(stroke
				(width 0.1524)
				(type default)
			)
			(layer "F.SilkS")
		)
		(fp_line
			(start -0.508 -0.9398)
			(end -0.508 0.9398)
			(stroke
				(width 0.1524)
				(type default)
			)
			(layer "F.SilkS")
		)
		(fp_rect
			(start -0.508 0.9398)
			(end 0.508 -0.9398)
			(stroke
				(width 0)
				(type default)
			)
			(fill no)
			(layer "F.CrtYd")
		)
		(fp_rect
			(start -0.508 0.9398)
			(end 0.508 -0.9398)
			(stroke
				(width 0)
				(type default)
			)
			(fill no)
			(layer "F.Fab")
		)
		(pad "1" smd custom
			(at 0 -0.4445 90)
			(size 0.1397 0.1397)
			(layers "F.Cu" "F.Mask" "F.Paste")
			(net "VDD_DIFF_4")
			(options
				(clearance outline)
				(anchor circle)
			)
			(primitives
				(gr_poly
					(pts
						(arc
							(start -0.1778 -0.2794)
							(mid -0.249642 -0.249642)
							(end -0.2794 -0.1778)
						)
						(arc
							(start -0.2794 0.1778)
							(mid -0.249642 0.249642)
							(end -0.1778 0.2794)
						)
						(arc
							(start 0.1778 0.2794)
							(mid 0.249642 0.249642)
							(end 0.2794 0.1778)
						)
						(arc
							(start 0.2794 -0.1778)
							(mid 0.249642 -0.249642)
							(end 0.1778 -0.2794)
						)
					)
					(width 0)
					(fill yes)
				)
			)
		)
		(pad "2" smd custom
			(at 0 0.4445 90)
			(size 0.1397 0.1397)
			(layers "F.Cu" "F.Mask" "F.Paste")
			(net "CLK_BUF_EU4_SMB_A1_TRI")
			(options
				(clearance outline)
				(anchor circle)
			)
			(primitives
				(gr_poly
					(pts
						(arc
							(start -0.1778 -0.2794)
							(mid -0.249642 -0.249642)
							(end -0.2794 -0.1778)
						)
						(arc
							(start -0.2794 0.1778)
							(mid -0.249642 0.249642)
							(end -0.1778 0.2794)
						)
						(arc
							(start 0.1778 0.2794)
							(mid 0.249642 0.249642)
							(end 0.2794 0.1778)
						)
						(arc
							(start 0.2794 -0.1778)
							(mid 0.249642 -0.249642)
							(end 0.1778 -0.2794)
						)
					)
					(width 0)
					(fill yes)
				)
			)
		)
	)
	(footprint ""
		(layer "F.Cu")
		(at 84.455 -203.962 -90)
		(property "Reference" "R9118"
			(at 0 0 270)
			(layer "F.SilkS")
			(hide yes)
			(effects
				(font
					(size 1.27 1.27)
				)
			)
		)
		(property "Value" "4K7R2F-GP"
			(at 0.064008 -3.993896 270)
			(unlocked yes)
			(layer "F.Fab")
			(hide yes)
			(effects
				(font
					(size 1.016 1.016)
					(thickness 0.1524)
				)
			)
		)
		(property "Device Type" "R402H16"
			(at 0.064008 -5.517896 270)
			(unlocked yes)
			(layer "F.Fab")
			(hide yes)
			(effects
				(font
					(size 1.016 1.016)
					(thickness 0.1524)
				)
			)
		)
		(duplicate_pad_numbers_are_jumpers no)
		(fp_line
			(start -0.508 -0.9398)
			(end -0.508 0.9398)
			(stroke
				(width 0.1524)
				(type default)
			)
			(layer "F.SilkS")
		)
		(fp_line
			(start 0.508 -0.9398)
			(end -0.508 -0.9398)
			(stroke
				(width 0.1524)
				(type default)
			)
			(layer "F.SilkS")
		)
		(fp_rect
			(start -0.508 0.9398)
			(end 0.508 -0.9398)
			(stroke
				(width 0)
				(type default)
			)
			(fill no)
			(layer "F.CrtYd")
		)
		(fp_rect
			(start -0.508 0.9398)
			(end 0.508 -0.9398)
			(stroke
				(width 0)
				(type default)
			)
			(fill no)
			(layer "F.Fab")
		)
		(pad "1" smd custom
			(at 0 -0.4445 270)
			(size 0.1397 0.1397)
			(layers "F.Cu" "F.Mask" "F.Paste")
			(net "CLK_BUF_EU3_SMB_A1_TRI")
			(options
				(clearance outline)
				(anchor circle)
			)
			(primitives
				(gr_poly
					(pts
						(arc
							(start -0.1778 -0.2794)
							(mid -0.249642 -0.249642)
							(end -0.2794 -0.1778)
						)
						(arc
							(start -0.2794 0.1778)
							(mid -0.249642 0.249642)
							(end -0.1778 0.2794)
						)
						(arc
							(start 0.1778 0.2794)
							(mid 0.249642 0.249642)
							(end 0.2794 0.1778)
						)
						(arc
							(start 0.2794 -0.1778)
							(mid 0.249642 -0.249642)
							(end 0.1778 -0.2794)
						)
					)
					(width 0)
					(fill yes)
				)
			)
		)
		(pad "2" smd custom
			(at 0 0.4445 270)
			(size 0.1397 0.1397)
			(layers "F.Cu" "F.Mask" "F.Paste")
			(net "GND")
			(options
				(clearance outline)
				(anchor circle)
			)
			(primitives
				(gr_poly
					(pts
						(arc
							(start -0.1778 -0.2794)
							(mid -0.249642 -0.249642)
							(end -0.2794 -0.1778)
						)
						(arc
							(start -0.2794 0.1778)
							(mid -0.249642 0.249642)
							(end -0.1778 0.2794)
						)
						(arc
							(start 0.1778 0.2794)
							(mid 0.249642 0.249642)
							(end 0.2794 0.1778)
						)
						(arc
							(start 0.2794 -0.1778)
							(mid 0.249642 -0.249642)
							(end 0.1778 -0.2794)
						)
					)
					(width 0)
					(fill yes)
				)
			)
		)
	)
	(footprint ""
		(layer "F.Cu")
		(at 70.000114 -276.497542)
		(property "Reference" "H4"
			(at 0 0 0)
			(layer "F.SilkS")
			(hide yes)
			(effects
				(font
					(size 1.27 1.27)
				)
			)
		)
		(property "Value" "GEN276X162R197X296-6-F-A-GP"
			(at -6.7183 4.1402 0)
			(unlocked yes)
			(layer "F.Fab")
			(hide yes)
			(effects
				(font
					(size 1.016 1.016)
					(thickness 0.1524)
				)
			)
		)
		(property "Device Type" "GEN276X162R197X296-6-F-A"
			(at -6.7183 2.6162 0)
			(unlocked yes)
			(layer "F.Fab")
			(hide yes)
			(effects
				(font
					(size 1.016 1.016)
					(thickness 0.1524)
				)
			)
		)
		(duplicate_pad_numbers_are_jumpers no)
		(fp_poly
			(pts
				(arc
					(start 2.723642 4.777232)
					(mid -0.000169 6.508462)
					(end -2.723896 4.776978)
				)
				(arc
					(start -2.723896 4.776978)
					(mid 0.000173 -5.499012)
					(end 2.723642 4.777232)
				)
			)
			(stroke
				(width 0)
				(type default)
			)
			(fill no)
			(layer "B.CrtYd")
		)
		(fp_poly
			(pts
				(arc
					(start 2.723642 4.777232)
					(mid -0.000169 6.508462)
					(end -2.723896 4.776978)
				)
				(arc
					(start -2.723896 4.776978)
					(mid 0.000173 -5.499012)
					(end 2.723642 4.777232)
				)
			)
			(stroke
				(width 0)
				(type default)
			)
			(fill no)
			(layer "F.CrtYd")
		)
		(fp_poly
			(pts
				(arc
					(start 2.723642 4.777232)
					(mid -0.000169 6.508462)
					(end -2.723896 4.776978)
				)
				(arc
					(start -2.723896 4.776978)
					(mid 0.000173 -5.499012)
					(end 2.723642 4.777232)
				)
			)
			(stroke
				(width 0)
				(type default)
			)
			(fill no)
			(layer "B.Fab")
		)
		(fp_poly
			(pts
				(arc
					(start 2.723642 4.777232)
					(mid -0.000169 6.508462)
					(end -2.723896 4.776978)
				)
				(arc
					(start -2.723896 4.776978)
					(mid 0.000173 -5.499012)
					(end 2.723642 4.777232)
				)
			)
			(stroke
				(width 0)
				(type default)
			)
			(fill no)
			(layer "F.Fab")
		)
		(pad "" np_thru_hole circle
			(at 0 0)
			(size 0.254 0.254)
			(drill 0.0254)
			(layers "*.Cu" "*.Mask")
			(clearance 3.135376)
			(thermal_gap 3.135376)
		)
		(pad "1" thru_hole circle
			(at 2.549906 0)
			(size 0.8636 0.8636)
			(drill 0.508)
			(layers "*.Cu" "*.Mask")
			(remove_unused_layers no)
			(net "GND")
			(clearance 0.8255)
			(thermal_gap 0.8255)
		)
		(pad "2" thru_hole circle
			(at 2.210054 -1.27)
			(size 0.8636 0.8636)
			(drill 0.508)
			(layers "*.Cu" "*.Mask")
			(remove_unused_layers no)
			(net "GND")
			(clearance 0.8255)
			(thermal_gap 0.8255)
		)
		(pad "3" thru_hole circle
			(at 1.27 -2.210054)
			(size 0.8636 0.8636)
			(drill 0.508)
			(layers "*.Cu" "*.Mask")
			(remove_unused_layers no)
			(net "GND")
			(clearance 0.8255)
			(thermal_gap 0.8255)
		)
		(pad "4" thru_hole circle
			(at -1.279906 -2.210054)
			(size 0.8636 0.8636)
			(drill 0.508)
			(layers "*.Cu" "*.Mask")
			(remove_unused_layers no)
			(net "GND")
			(clearance 0.8255)
			(thermal_gap 0.8255)
		)
		(pad "5" thru_hole circle
			(at -2.210054 -1.27)
			(size 0.8636 0.8636)
			(drill 0.508)
			(layers "*.Cu" "*.Mask")
			(remove_unused_layers no)
			(net "GND")
			(clearance 0.8255)
			(thermal_gap 0.8255)
		)
		(pad "6" thru_hole circle
			(at -2.549906 0)
			(size 0.8636 0.8636)
			(drill 0.508)
			(layers "*.Cu" "*.Mask")
			(remove_unused_layers no)
			(net "GND")
			(clearance 0.8255)
			(thermal_gap 0.8255)
		)
		(zone
			(layers "F.Cu" "B.Cu" "In1.Cu" "In2.Cu" "In3.Cu" "In4.Cu" "In5.Cu" "In6.Cu")
			(hatch none 0.5)
			(connect_pads
				(clearance 0)
			)
			(min_thickness 0.25)
			(keepout
				(tracks allowed)
				(vias not_allowed)
				(pads allowed)
				(copperpour not_allowed)
				(footprints allowed)
			)
			(placement
				(enabled no)
				(sheetname "")
			)
			(fill
				(thermal_gap 0.5)
				(thermal_bridge_width 0.5)
				(island_removal_mode 0)
			)
			(polygon
				(pts
					(arc
						(start 74.318114 -276.50059)
						(mid 65.682114 -276.50059)
						(end 74.318114 -276.50059)
					)
				)
			)
		)
		(zone
			(layers "F.Cu" "B.Cu" "In1.Cu" "In2.Cu" "In3.Cu" "In4.Cu" "In5.Cu" "In6.Cu")
			(hatch none 0.5)
			(connect_pads
				(clearance 0)
			)
			(min_thickness 0.25)
			(keepout
				(tracks not_allowed)
				(vias allowed)
				(pads allowed)
				(copperpour not_allowed)
				(footprints allowed)
			)
			(placement
				(enabled no)
				(sheetname "")
			)
			(fill
				(thermal_gap 0.5)
				(thermal_bridge_width 0.5)
				(island_removal_mode 0)
			)
			(polygon
				(pts
					(arc
						(start 72.339454 -274.888198)
						(mid 70.000194 -269.989095)
						(end 67.66052 -274.888198)
					)
					(arc
						(start 67.66052 -274.888198)
						(mid 67.906487 -275.328564)
						(end 67.991736 -275.825712)
					)
					(arc
						(start 67.991736 -276.497542)
						(mid 70.000114 -278.50592)
						(end 72.008238 -276.497542)
					)
					(arc
						(start 72.008238 -275.825712)
						(mid 72.093473 -275.328558)
						(end 72.339454 -274.888198)
					)
				)
			)
		)
	)
	(footprint ""
		(layer "F.Cu")
		(at 220.726 -447.04)
		(property "Reference" "Q28"
			(at 0 0 0)
			(layer "F.SilkS")
			(hide yes)
			(effects
				(font
					(size 1.27 1.27)
				)
			)
		)
		(property "Value" "2N7002A-7-GP"
			(at 0.127 -8.9662 0)
			(unlocked yes)
			(layer "F.Fab")
			(hide yes)
			(effects
				(font
					(size 1.016 1.016)
					(thickness 0.1524)
				)
			)
		)
		(property "Device Type" "SOT23DGS2D4H48"
			(at 0.127 -10.4902 0)
			(unlocked yes)
			(layer "F.Fab")
			(hide yes)
			(effects
				(font
					(size 1.016 1.016)
					(thickness 0.1524)
				)
			)
		)
		(duplicate_pad_numbers_are_jumpers no)
		(fp_line
			(start -1.651 -1.778)
			(end -1.651 1.778)
			(stroke
				(width 0.1524)
				(type default)
			)
			(layer "F.SilkS")
		)
		(fp_line
			(start -1.651 1.778)
			(end 1.651 1.778)
			(stroke
				(width 0.1524)
				(type default)
			)
			(layer "F.SilkS")
		)
		(fp_line
			(start 1.651 -1.778)
			(end -1.651 -1.778)
			(stroke
				(width 0.1524)
				(type default)
			)
			(layer "F.SilkS")
		)
		(fp_line
			(start 1.651 1.778)
			(end 1.651 -1.778)
			(stroke
				(width 0.1524)
				(type default)
			)
			(layer "F.SilkS")
		)
		(fp_poly
			(pts
				(xy -1.778 1.8796) (xy -1.778 -1.8796) (xy 1.778 -1.8796) (xy 1.778 1.8796)
			)
			(stroke
				(width 0)
				(type default)
			)
			(fill no)
			(layer "F.CrtYd")
		)
		(fp_poly
			(pts
				(xy -1.778 1.8796) (xy -1.778 -1.8796) (xy 1.778 -1.8796) (xy 1.778 1.8796)
			)
			(stroke
				(width 0)
				(type default)
			)
			(fill no)
			(layer "F.Fab")
		)
		(pad "D" smd custom
			(at 0 -0.9525)
			(size 0.1905 0.1905)
			(layers "F.Cu" "F.Mask" "F.Paste")
			(net "SSD0_CLK0_OE_MOS_N")
			(options
				(clearance outline)
				(anchor circle)
			)
			(primitives
				(gr_poly
					(pts
						(arc
							(start -0.1778 0.5715)
							(mid -0.321484 0.511984)
							(end -0.381 0.3683)
						)
						(arc
							(start -0.381 -0.3683)
							(mid -0.321484 -0.511984)
							(end -0.1778 -0.5715)
						)
						(arc
							(start 0.1778 -0.5715)
							(mid 0.321484 -0.511984)
							(end 0.381 -0.3683)
						)
						(arc
							(start 0.381 0.3683)
							(mid 0.321484 0.511984)
							(end 0.1778 0.5715)
						)
					)
					(width 0)
					(fill yes)
				)
			)
		)
		(pad "G" smd custom
			(at -0.98425 0.9525)
			(size 0.1905 0.1905)
			(layers "F.Cu" "F.Mask" "F.Paste")
			(net "SSD0_CLK0_OE_R_N")
			(options
				(clearance outline)
				(anchor circle)
			)
			(primitives
				(gr_poly
					(pts
						(arc
							(start -0.1778 0.5715)
							(mid -0.321484 0.511984)
							(end -0.381 0.3683)
						)
						(arc
							(start -0.381 -0.3683)
							(mid -0.321484 -0.511984)
							(end -0.1778 -0.5715)
						)
						(arc
							(start 0.1778 -0.5715)
							(mid 0.321484 -0.511984)
							(end 0.381 -0.3683)
						)
						(arc
							(start 0.381 0.3683)
							(mid 0.321484 0.511984)
							(end 0.1778 0.5715)
						)
					)
					(width 0)
					(fill yes)
				)
			)
		)
		(pad "S" smd custom
			(at 0.98425 0.9525)
			(size 0.1905 0.1905)
			(layers "F.Cu" "F.Mask" "F.Paste")
			(net "GND")
			(options
				(clearance outline)
				(anchor circle)
			)
			(primitives
				(gr_poly
					(pts
						(arc
							(start -0.1778 0.5715)
							(mid -0.321484 0.511984)
							(end -0.381 0.3683)
						)
						(arc
							(start -0.381 -0.3683)
							(mid -0.321484 -0.511984)
							(end -0.1778 -0.5715)
						)
						(arc
							(start 0.1778 -0.5715)
							(mid 0.321484 -0.511984)
							(end 0.381 -0.3683)
						)
						(arc
							(start 0.381 0.3683)
							(mid 0.321484 0.511984)
							(end 0.1778 0.5715)
						)
					)
					(width 0)
					(fill yes)
				)
			)
		)
	)
	(footprint ""
		(layer "F.Cu")
		(at 42.203116 -35.167062 90)
		(property "Reference" "U206"
			(at 0 0 90)
			(layer "F.SilkS")
			(hide yes)
			(effects
				(font
					(size 1.27 1.27)
				)
			)
		)
		(property "Value" "SN74LVC1G08DCKR-GP"
			(at -2.3368 -8.6868 90)
			(unlocked yes)
			(layer "F.Fab")
			(hide yes)
			(effects
				(font
					(size 1.016 1.016)
					(thickness 0.1524)
				)
			)
		)
		(property "Device Type" "SC70-5H44"
			(at -2.3114 -10.414 90)
			(unlocked yes)
			(layer "F.Fab")
			(hide yes)
			(effects
				(font
					(size 1.016 1.016)
					(thickness 0.1524)
				)
			)
		)
		(duplicate_pad_numbers_are_jumpers no)
		(fp_line
			(start 1.3843 -1.8034)
			(end 1.3843 -1.1176)
			(stroke
				(width 0.3302)
				(type default)
			)
			(layer "F.SilkS")
		)
		(fp_line
			(start 0.6604 -1.8034)
			(end 1.3843 -1.8034)
			(stroke
				(width 0.3302)
				(type default)
			)
			(layer "F.SilkS")
		)
		(fp_line
			(start 1.27 -1.7018)
			(end 1.27 1.7018)
			(stroke
				(width 0.1524)
				(type default)
			)
			(layer "F.SilkS")
		)
		(fp_line
			(start -1.27 -1.7018)
			(end 1.27 -1.7018)
			(stroke
				(width 0.1524)
				(type default)
			)
			(layer "F.SilkS")
		)
		(fp_line
			(start 1.27 1.7018)
			(end -1.27 1.7018)
			(stroke
				(width 0.1524)
				(type default)
			)
			(layer "F.SilkS")
		)
		(fp_line
			(start -1.27 1.7018)
			(end -1.27 -1.7018)
			(stroke
				(width 0.1524)
				(type default)
			)
			(layer "F.SilkS")
		)
		(fp_rect
			(start -1.524 1.9558)
			(end 1.524 -1.9558)
			(stroke
				(width 0)
				(type default)
			)
			(fill no)
			(layer "F.CrtYd")
		)
		(fp_poly
			(pts
				(xy -1.524 -1.9558) (xy 1.524 -1.9558) (xy 1.524 1.9558) (xy -1.524 1.9558)
			)
			(stroke
				(width 0)
				(type default)
			)
			(fill no)
			(layer "F.Fab")
		)
		(pad "1" smd rect
			(at 0.65024 -0.8255 90)
			(size 0.4064 1.2192)
			(layers "F.Cu" "F.Mask" "F.Paste")
			(net "SSD9_CLK0_OE_MOS_N")
		)
		(pad "2" smd rect
			(at 0 -0.8255 90)
			(size 0.4064 1.2192)
			(layers "F.Cu" "F.Mask" "F.Paste")
			(net "ATTN_LED_DR9_N")
		)
		(pad "3" smd rect
			(at -0.65024 -0.8255 90)
			(size 0.4064 1.2192)
			(layers "F.Cu" "F.Mask" "F.Paste")
			(net "GND")
		)
		(pad "4" smd rect
			(at -0.65024 0.8255 90)
			(size 0.4064 1.2192)
			(layers "F.Cu" "F.Mask" "F.Paste")
			(net "ATTN_LED_DR9_AND")
		)
		(pad "5" smd rect
			(at 0.65024 0.8255 90)
			(size 0.4064 1.2192)
			(layers "F.Cu" "F.Mask" "F.Paste")
			(net "P3V3")
		)
	)
)
